#ISCELL
  pure_quanta quanta_title_block_c *
  *
#CELL
  pure_quanta q_cap *
  page77_i1
#CELL
  pure_quanta q_cap *
  page77_i10
#CELL
  pure_quanta q_cap *
  page77_i100
#CELL
  pure_quanta q_cap *
  page77_i101
#CELL
  pure_quanta q_cap *
  page77_i102
#CELL
  pure_quanta q_cap *
  page77_i103
#CELL
  pure_quanta q_cap *
  page77_i104
#CELL
  pure_quanta q_cap *
  page77_i105
#CELL
  pure_quanta q_cap *
  page77_i106
#ISCELL
  logical_power universal_power *
  page77_i107
#ISCELL
  logical_power universal_gnd *
  page77_i108
#CELL
  pure_quanta q_cap *
  page77_i109
#CELL
  pure_quanta q_cap *
  page77_i11
#CELL
  pure_quanta q_cap *
  page77_i110
#CELL
  pure_quanta q_cap *
  page77_i111
#CELL
  pure_quanta q_cap *
  page77_i112
#CELL
  pure_quanta q_cap *
  page77_i113
#CELL
  pure_quanta q_cap *
  page77_i114
#CELL
  pure_quanta q_cap *
  page77_i115
#ISCELL
  logical_power universal_gnd *
  page77_i116
#CELL
  pure_quanta q_cap *
  page77_i117
#CELL
  pure_quanta q_cap *
  page77_i118
#CELL
  pure_quanta q_cap *
  page77_i119
#ISCELL
  logical_power universal_power *
  page77_i12
#CELL
  pure_quanta q_cap *
  page77_i120
#CELL
  pure_quanta q_cap *
  page77_i121
#CELL
  pure_quanta q_cap *
  page77_i122
#CELL
  pure_quanta q_cap *
  page77_i123
#CELL
  pure_quanta q_cap *
  page77_i124
#CELL
  pure_quanta q_cap *
  page77_i125
#CELL
  pure_quanta q_cap *
  page77_i126
#CELL
  pure_quanta q_cap *
  page77_i127
#CELL
  pure_quanta q_cap *
  page77_i128
#CELL
  pure_quanta q_cap *
  page77_i129
#CELL
  pure_quanta q_cap *
  page77_i13
#CELL
  pure_quanta q_cap *
  page77_i130
#CELL
  pure_quanta q_cap *
  page77_i131
#CELL
  pure_quanta q_cap *
  page77_i132
#CELL
  pure_quanta q_cap *
  page77_i133
#CELL
  pure_quanta q_cap *
  page77_i134
#ISCELL
  logical_power universal_gnd *
  page77_i135
#CELL
  pure_quanta q_cap *
  page77_i136
#ISCELL
  logical_power universal_gnd *
  page77_i137
#CELL
  pure_quanta q_cap *
  page77_i138
#CELL
  pure_quanta q_cap *
  page77_i139
#CELL
  pure_quanta q_cap *
  page77_i14
#CELL
  pure_quanta q_cap *
  page77_i140
#ISCELL
  logical_power universal_gnd *
  page77_i141
#CELL
  pure_quanta q_cap *
  page77_i142
#CELL
  pure_quanta q_cap *
  page77_i15
#CELL
  pure_quanta q_cap *
  page77_i16
#CELL
  pure_quanta q_cap *
  page77_i17
#CELL
  pure_quanta q_cap *
  page77_i18
#CELL
  pure_quanta q_cap *
  page77_i19
#CELL
  pure_quanta q_cap *
  page77_i2
#CELL
  pure_quanta q_cap *
  page77_i20
#ISCELL
  logical_power universal_power *
  page77_i21
#CELL
  pure_quanta q_cap *
  page77_i22
#CELL
  pure_quanta q_cap *
  page77_i23
#ISCELL
  logical_power universal_power *
  page77_i24
#CELL
  pure_quanta q_cap *
  page77_i25
#CELL
  pure_quanta q_cap *
  page77_i26
#ISCELL
  logical_power universal_power *
  page77_i27
#CELL
  pure_quanta q_cap *
  page77_i28
#CELL
  pure_quanta q_cap *
  page77_i29
#ISCELL
  logical_power universal_power *
  page77_i3
#CELL
  pure_quanta q_cap *
  page77_i30
#CELL
  pure_quanta q_cap *
  page77_i31
#CELL
  pure_quanta q_cap *
  page77_i32
#CELL
  pure_quanta q_cap *
  page77_i33
#CELL
  pure_quanta q_cap *
  page77_i34
#CELL
  pure_quanta q_cap *
  page77_i35
#ISCELL
  logical_power universal_power *
  page77_i36
#CELL
  pure_quanta q_cap *
  page77_i37
#CELL
  pure_quanta q_cap *
  page77_i38
#CELL
  pure_quanta q_cap *
  page77_i39
#CELL
  pure_quanta q_cap *
  page77_i4
#CELL
  pure_quanta q_cap *
  page77_i40
#CELL
  pure_quanta q_cap *
  page77_i41
#CELL
  pure_quanta q_cap *
  page77_i42
#ISCELL
  logical_power universal_power *
  page77_i43
#CELL
  pure_quanta q_cap *
  page77_i44
#CELL
  pure_quanta q_cap *
  page77_i45
#CELL
  pure_quanta q_cap *
  page77_i46
#CELL
  pure_quanta q_cap *
  page77_i47
#CELL
  pure_quanta q_cap *
  page77_i48
#CELL
  pure_quanta q_cap *
  page77_i49
#CELL
  pure_quanta q_cap *
  page77_i5
#CELL
  pure_quanta q_cap *
  page77_i50
#CELL
  pure_quanta q_cap *
  page77_i51
#CELL
  pure_quanta q_cap *
  page77_i52
#CELL
  pure_quanta q_cap *
  page77_i53
#ISCELL
  logical_power universal_gnd *
  page77_i54
#CELL
  pure_quanta q_cap *
  page77_i55
#ISCELL
  logical_power universal_gnd *
  page77_i56
#CELL
  pure_quanta q_cap *
  page77_i57
#CELL
  pure_quanta q_cap *
  page77_i58
#CELL
  pure_quanta q_cap *
  page77_i59
#ISCELL
  logical_power universal_gnd *
  page77_i6
#ISCELL
  logical_power universal_gnd *
  page77_i60
#CELL
  pure_quanta q_cap *
  page77_i61
#CELL
  pure_quanta q_cap *
  page77_i62
#CELL
  pure_quanta q_cap *
  page77_i63
#CELL
  pure_quanta q_cap *
  page77_i64
#ISCELL
  logical_power universal_gnd *
  page77_i65
#CELL
  pure_quanta q_cap *
  page77_i66
#CELL
  pure_quanta q_cap *
  page77_i67
#ISCELL
  logical_power universal_power *
  page77_i68
#ISCELL
  logical_power universal_gnd *
  page77_i69
#CELL
  pure_quanta q_cap *
  page77_i7
#CELL
  pure_quanta q_cap *
  page77_i70
#CELL
  pure_quanta q_cap *
  page77_i71
#ISCELL
  logical_power universal_power *
  page77_i72
#CELL
  pure_quanta q_cap *
  page77_i73
#CELL
  pure_quanta q_cap *
  page77_i74
#CELL
  pure_quanta q_cap *
  page77_i75
#CELL
  pure_quanta q_cap *
  page77_i76
#CELL
  pure_quanta q_cap *
  page77_i77
#CELL
  pure_quanta q_cap *
  page77_i78
#CELL
  pure_quanta q_cap *
  page77_i79
#CELL
  pure_quanta q_cap *
  page77_i8
#CELL
  pure_quanta q_cap *
  page77_i80
#CELL
  pure_quanta q_cap *
  page77_i81
#CELL
  pure_quanta q_cap *
  page77_i82
#CELL
  pure_quanta q_cap *
  page77_i83
#CELL
  pure_quanta q_cap *
  page77_i84
#CELL
  pure_quanta q_cap *
  page77_i85
#CELL
  pure_quanta q_cap *
  page77_i86
#ISCELL
  logical_power universal_gnd *
  page77_i87
#CELL
  pure_quanta q_cap *
  page77_i88
#ISCELL
  logical_power universal_gnd *
  page77_i89
#ISCELL
  logical_power universal_power *
  page77_i9
#ISCELL
  logical_power universal_power *
  page77_i90
#CELL
  pure_quanta q_cap *
  page77_i91
#ISCELL
  logical_power universal_power *
  page77_i92
#CELL
  pure_quanta q_cap *
  page77_i93
#CELL
  pure_quanta q_cap *
  page77_i94
#CELL
  pure_quanta q_cap *
  page77_i95
#ISCELL
  logical_power universal_gnd *
  page77_i96
#CELL
  pure_quanta q_cap *
  page77_i97
#CELL
  pure_quanta q_cap *
  page77_i98
#ISCELL
  logical_power universal_power *
  page77_i99
